FILE_TYPE = MACRO_DRAWING;
SET COLOR_WIRE YELLOW;
SET COLOR_PROP ORANGE;
SET COLOR_DOT WHITE;
SET COLOR_ARC YELLOW;
SET COLOR_BODY GREEN;
SET COLOR_NOTE PURPLE;
SET PROP_DISPLAY VALUE;
SET PAGE_NUMBER P156;
FORCEADD Q_RES..2
(-6550 7275);
FORCEPROP 1 LAST LOCATION R5052
J 0
(-6505 7400);
DISPLAY 0.638298 (-6505 7400);
FORCEPROP 0 LAST $SEC 1
J 0
(-6500 7450);
DISPLAY 0.680851 (-6500 7450);
PAINT MONO (-6500 7450);
DISPLAY INVISIBLE (-6500 7450);
FORCEPROP 0 LAST CDS_SEC 1
J 0
(-6500 7450);
DISPLAY 0.680851 (-6500 7450);
DISPLAY INVISIBLE (-6500 7450);
FORCEPROP 1 LASTPIN (-6550 7375) $PN 1
J 0
(-6545 7337);
DISPLAY 0.787234 (-6545 7337);
PAINT MONO (-6545 7337);
FORCEPROP 1 LASTPIN (-6550 7175) $PN 2
J 0
(-6545 7185);
DISPLAY 0.787234 (-6545 7185);
PAINT MONO (-6545 7185);
FORCEPROP 1 LAST WATTAGE 1/16W
J 0
(-6510 7250);
DISPLAY 0.638298 (-6510 7250);
FORCEPROP 1 LAST TOLERANCE 5%
J 0
(-6505 7300);
DISPLAY 0.638298 (-6505 7300);
FORCEPROP 1 LAST VALUE 0
J 0
(-6505 7350);
DISPLAY 0.638298 (-6505 7350);
FORCEPROP 1 LAST PACK_TYPE 0402LF
J 0
(-6510 7100);
DISPLAY 0.638298 (-6510 7100);
FORCEPROP 1 LAST MATERIAL CHIP
J 0
(-6510 7200);
DISPLAY 0.638298 (-6510 7200);
FORCEPROP 2 LAST CDS_LIB pure_quanta
J 0
(-6550 7275);
DISPLAY INVISIBLE (-6550 7275);
FORCEPROP 1 LAST PATH I100
J 0
(-6500 7450);
DISPLAY 0.978723 (-6500 7450);
PAINT WHITE (-6500 7450);
DISPLAY INVISIBLE (-6500 7450);
FORCEPROP 1 LAST PART_NUMBER CS00002JB13
J 0
(-6510 7150);
DISPLAY 0.638298 (-6510 7150);
DISPLAY INVISIBLE (-6510 7150);
FORCEADD Q_RES..1
(-6325 7000);
FORCEPROP 1 LAST LOCATION R5051
J 0
(-6450 6950);
DISPLAY 0.638298 (-6450 6950);
FORCEPROP 0 LAST $SEC 1
J 0
(-6150 7000);
DISPLAY 0.680851 (-6150 7000);
PAINT MONO (-6150 7000);
DISPLAY INVISIBLE (-6150 7000);
FORCEPROP 0 LAST CDS_SEC 1
J 0
(-6150 7000);
DISPLAY 0.680851 (-6150 7000);
DISPLAY INVISIBLE (-6150 7000);
FORCEPROP 1 LASTPIN (-6425 7000) $PN 1
J 0
(-6413 7012);
DISPLAY 0.787234 (-6413 7012);
PAINT MONO (-6413 7012);
FORCEPROP 1 LASTPIN (-6225 7000) $PN 2
J 0
(-6263 7012);
DISPLAY 0.787234 (-6263 7012);
PAINT MONO (-6263 7012);
FORCEPROP 1 LAST MATERIAL EMPTY
J 0
(-6300 6875);
DISPLAY 0.638298 (-6300 6875);
PAINT RED (-6300 6875);
FORCEPROP 1 LAST WATTAGE 1/16W
J 2
(-6350 6875);
DISPLAY 0.638298 (-6350 6875);
FORCEPROP 1 LAST VALUE 0
J 2
(-6200 6950);
DISPLAY 0.638298 (-6200 6950);
FORCEPROP 1 LAST TOLERANCE 5%
J 0
(-6150 6950);
DISPLAY 0.638298 (-6150 6950);
FORCEPROP 1 LAST PACK_TYPE 0402LF
J 0
(-6400 6825);
DISPLAY 0.638298 (-6400 6825);
FORCEPROP 2 LAST CDS_LIB pure_quanta
J 0
(-6325 7000);
DISPLAY INVISIBLE (-6325 7000);
FORCEPROP 1 LAST PATH I101
J 0
(-6375 7150);
DISPLAY 0.978723 (-6375 7150);
PAINT WHITE (-6375 7150);
DISPLAY INVISIBLE (-6375 7150);
FORCEPROP 1 LAST PART_NUMBER CS00002JB13
J 0
(-6475 6925);
DISPLAY 0.638298 (-6475 6925);
DISPLAY INVISIBLE (-6475 6925);
FORCEADD UNIVERSAL_POWER..1
(-6850 7850);
FORCEPROP 3 LASTPIN (-6850 7800) SIG_NAME P3V3_RTC_AUX\g
J 0
(-6840 7810);
DISPLAY 0.659574 (-6840 7810);
PAINT MONO (-6840 7810);
DISPLAY INVISIBLE (-6840 7810);
FORCEPROP 1 LAST HDL_POWER P3V3_RTC_AUX
J 1
(-6850 7900);
DISPLAY 0.489362 (-6850 7900);
PAINT GREEN (-6850 7900);
FORCEPROP 2 LAST CDS_LIB pure_quanta_power
J 0
(-6850 7850);
DISPLAY INVISIBLE (-6850 7850);
FORCEPROP 1 LAST PATH I102
J 0
(-6800 7875);
DISPLAY 0.872340 (-6800 7875);
PAINT AQUA (-6800 7875);
DISPLAY INVISIBLE (-6800 7875);
FORCEADD UNIVERSAL_GND..1
R 5
(-5650 5075);
FORCEPROP 3 LASTPIN (-5600 5075) SIG_NAME GND\g
J 0
(-5590 5085);
DISPLAY 0.659574 (-5590 5085);
PAINT MONO (-5590 5085);
DISPLAY INVISIBLE (-5590 5085);
FORCEPROP 2 LAST CDS_LIB pure_quanta_power
R 3
J 0
(-5650 5075);
DISPLAY INVISIBLE (-5650 5075);
FORCEPROP 1 LAST HDL_POWER GND
R 3
J 1
(-5725 5050);
DISPLAY 0.872340 (-5725 5050);
PAINT GREEN (-5725 5050);
DISPLAY INVISIBLE (-5725 5050);
FORCEPROP 1 LAST PATH I103
R 3
J 0
(-5650 5000);
DISPLAY 0.872340 (-5650 5000);
PAINT AQUA (-5650 5000);
DISPLAY INVISIBLE (-5650 5000);
FORCEADD MOSFET_DUAL_6P..1
(-5300 5025);
FORCEPROP 1 LAST LOCATION Q8
J 0
(-5447 5234);
DISPLAY 0.489362 (-5447 5234);
PAINT SKYBLUE (-5447 5234);
FORCEPROP 2 LAST $SEC 1
J 0
(-5425 5375);
DISPLAY 0.680851 (-5425 5375);
PAINT MONO (-5425 5375);
DISPLAY INVISIBLE (-5425 5375);
FORCEPROP 2 LAST CDS_SEC 1
J 0
(-5425 5375);
DISPLAY 0.680851 (-5425 5375);
DISPLAY INVISIBLE (-5425 5375);
FORCEPROP 2 LASTPIN (-5600 4975) $PN 6
J 2
(-5610 4985);
DISPLAY 0.489362 (-5610 4985);
PAINT MONO (-5610 4985);
FORCEPROP 2 LASTPIN (-5000 4975) $PN 3
J 0
(-4990 4985);
DISPLAY 0.489362 (-4990 4985);
PAINT MONO (-4990 4985);
FORCEPROP 2 LASTPIN (-5600 5025) $PN 2
J 2
(-5610 5035);
DISPLAY 0.489362 (-5610 5035);
PAINT MONO (-5610 5035);
FORCEPROP 2 LASTPIN (-5000 5025) $PN 5
J 0
(-4990 5035);
DISPLAY 0.489362 (-4990 5035);
PAINT MONO (-4990 5035);
FORCEPROP 2 LASTPIN (-5600 5075) $PN 1
J 2
(-5610 5085);
DISPLAY 0.489362 (-5610 5085);
PAINT MONO (-5610 5085);
FORCEPROP 2 LASTPIN (-5000 5075) $PN 4
J 0
(-4990 5085);
DISPLAY 0.489362 (-4990 5085);
PAINT MONO (-4990 5085);
FORCEPROP 2 LAST VALUE 2N7002KDW
J 0
(-5425 5275);
DISPLAY 0.489362 (-5425 5275);
PAINT SKYBLUE (-5425 5275);
FORCEPROP 2 LAST PART_TYPE SMLF
J 0
(-5425 5325);
DISPLAY 0.680851 (-5425 5325);
FORCEPROP 1 LAST MATERIAL IC
J 0
(-5447 5148);
DISPLAY 0.489362 (-5447 5148);
PAINT SKYBLUE (-5447 5148);
FORCEPROP 1 LAST CDS_LMAN_SYM_OUTLINE -150,100,150,-100
J 0
(-5300 5025);
DISPLAY 0.468085 (-5300 5025);
PAINT GREEN (-5300 5025);
DISPLAY INVISIBLE (-5300 5025);
FORCEPROP 1 LAST NEEDS_NO_SIZE TRUE
J 0
(-5300 5024);
DISPLAY 0.468085 (-5300 5024);
PAINT GREEN (-5300 5024);
DISPLAY INVISIBLE (-5300 5024);
FORCEPROP 2 LAST CDS_LIB pure_quanta
J 0
(-5300 5025);
DISPLAY INVISIBLE (-5300 5025);
FORCEPROP 1 LAST PATH I104
J 0
(-5300 5025);
DISPLAY 0.723404 (-5300 5025);
PAINT GREEN (-5300 5025);
DISPLAY INVISIBLE (-5300 5025);
FORCEPROP 1 LAST PART_NUMBER BAM70020047
J 0
(-5447 5192);
DISPLAY 0.489362 (-5447 5192);
PAINT SKYBLUE (-5447 5192);
DISPLAY INVISIBLE (-5447 5192);
FORCEADD UNIVERSAL_GND..1
R 1
(-4950 5075);
FORCEPROP 3 LASTPIN (-5000 5075) SIG_NAME GND\g
J 0
(-4990 5085);
DISPLAY 0.659574 (-4990 5085);
PAINT MONO (-4990 5085);
DISPLAY INVISIBLE (-4990 5085);
FORCEPROP 2 LAST CDS_LIB pure_quanta_power
R 1
J 0
(-4950 5075);
DISPLAY INVISIBLE (-4950 5075);
FORCEPROP 1 LAST HDL_POWER GND
R 1
J 1
(-4875 5100);
DISPLAY 0.872340 (-4875 5100);
PAINT GREEN (-4875 5100);
DISPLAY INVISIBLE (-4875 5100);
FORCEPROP 1 LAST PATH I105
R 1
J 0
(-4950 5150);
DISPLAY 0.872340 (-4950 5150);
PAINT AQUA (-4950 5150);
DISPLAY INVISIBLE (-4950 5150);
FORCEADD UNIVERSAL_GND..1
(-5425 6300);
FORCEPROP 3 LASTPIN (-5425 6350) SIG_NAME GND\g
J 0
(-5415 6360);
DISPLAY 0.659574 (-5415 6360);
PAINT MONO (-5415 6360);
DISPLAY INVISIBLE (-5415 6360);
FORCEPROP 2 LAST CDS_LIB pure_quanta_power
J 0
(-5425 6300);
DISPLAY INVISIBLE (-5425 6300);
FORCEPROP 1 LAST HDL_POWER GND
J 1
(-5400 6225);
DISPLAY 0.872340 (-5400 6225);
PAINT GREEN (-5400 6225);
DISPLAY INVISIBLE (-5400 6225);
FORCEPROP 1 LAST PATH I106
J 0
(-5350 6300);
DISPLAY 0.872340 (-5350 6300);
PAINT AQUA (-5350 6300);
DISPLAY INVISIBLE (-5350 6300);
FORCEADD Q_CAP..1
R 2
(-5425 6775);
FORCEPROP 1 LAST LOCATION C45
J 2
(-5475 6875);
DISPLAY 0.489362 (-5475 6875);
PAINT SKYBLUE (-5475 6875);
FORCEPROP 2 LAST $SEC 1
J 2
(-5475 6975);
DISPLAY 0.680851 (-5475 6975);
PAINT MONO (-5475 6975);
DISPLAY INVISIBLE (-5475 6975);
FORCEPROP 2 LAST CDS_SEC 1
J 2
(-5475 6975);
DISPLAY 0.680851 (-5475 6975);
DISPLAY INVISIBLE (-5475 6975);
FORCEPROP 1 LASTPIN (-5425 6875) $PN 1
J 2
(-5435 6855);
DISPLAY 0.489362 (-5435 6855);
FORCEPROP 1 LASTPIN (-5425 6675) $PN 2
J 2
(-5435 6655);
DISPLAY 0.489362 (-5435 6655);
FORCEPROP 1 LAST PACK_TYPE C0402
J 2
(-5475 6575);
DISPLAY 0.489362 (-5475 6575);
PAINT SKYBLUE (-5475 6575);
FORCEPROP 1 LAST VALUE 1UF
J 2
(-5475 6825);
DISPLAY 0.489362 (-5475 6825);
PAINT SKYBLUE (-5475 6825);
FORCEPROP 1 LAST VOLTAGE 25V
J 2
(-5475 6775);
DISPLAY 0.489362 (-5475 6775);
PAINT SKYBLUE (-5475 6775);
FORCEPROP 1 LAST TOLERANCE 10%
J 2
(-5475 6725);
DISPLAY 0.489362 (-5475 6725);
PAINT SKYBLUE (-5475 6725);
FORCEPROP 1 LAST MATERIAL X6S
J 2
(-5475 6675);
DISPLAY 0.489362 (-5475 6675);
PAINT SKYBLUE (-5475 6675);
FORCEPROP 2 LAST CDS_LIB pure_quanta
J 2
(-5425 6775);
DISPLAY INVISIBLE (-5425 6775);
FORCEPROP 1 LAST PATH I107
J 2
(-5475 6925);
DISPLAY 0.978723 (-5475 6925);
PAINT WHITE (-5475 6925);
DISPLAY INVISIBLE (-5475 6925);
FORCEPROP 1 LAST PART_NUMBER CH5104KEB02
J 2
(-5475 6625);
DISPLAY 0.489362 (-5475 6625);
PAINT SKYBLUE (-5475 6625);
DISPLAY INVISIBLE (-5475 6625);
FORCEADD Q_CAP..1
R 2
(-5250 6800);
FORCEPROP 1 LAST LOCATION C193
J 0
(-5175 6900);
DISPLAY 0.489362 (-5175 6900);
PAINT SKYBLUE (-5175 6900);
FORCEPROP 0 LAST $SEC 1
J 0
(-5300 6950);
PAINT MONO (-5300 6950);
DISPLAY INVISIBLE (-5300 6950);
FORCEPROP 0 LAST CDS_SEC 1
J 0
(-5300 6950);
PAINT MONO (-5300 6950);
DISPLAY INVISIBLE (-5300 6950);
FORCEPROP 1 LASTPIN (-5250 6900) $PN 1
J 2
(-5260 6880);
DISPLAY 0.489362 (-5260 6880);
PAINT GREEN (-5260 6880);
FORCEPROP 1 LASTPIN (-5250 6700) $PN 2
J 2
(-5260 6680);
DISPLAY 0.489362 (-5260 6680);
PAINT GREEN (-5260 6680);
FORCEPROP 1 LAST PACK_TYPE C0402
J 0
(-5175 6600);
DISPLAY 0.489362 (-5175 6600);
PAINT SKYBLUE (-5175 6600);
FORCEPROP 1 LAST VALUE 100NF
J 0
(-5175 6850);
DISPLAY 0.489362 (-5175 6850);
PAINT SKYBLUE (-5175 6850);
FORCEPROP 1 LAST VOLTAGE 50V
J 0
(-5175 6800);
DISPLAY 0.489362 (-5175 6800);
PAINT SKYBLUE (-5175 6800);
FORCEPROP 1 LAST TOLERANCE 10%
J 0
(-5175 6750);
DISPLAY 0.489362 (-5175 6750);
PAINT SKYBLUE (-5175 6750);
FORCEPROP 1 LAST MATERIAL X7R
J 0
(-5175 6700);
DISPLAY 0.489362 (-5175 6700);
PAINT SKYBLUE (-5175 6700);
FORCEPROP 2 LAST CDS_LIB pure_quanta
J 0
(-5250 6800);
PAINT MONO (-5250 6800);
DISPLAY INVISIBLE (-5250 6800);
FORCEPROP 1 LAST PATH I108
J 2
(-5300 6950);
DISPLAY 0.978723 (-5300 6950);
PAINT WHITE (-5300 6950);
DISPLAY INVISIBLE (-5300 6950);
FORCEPROP 1 LAST PART_NUMBER CH4106K1B01
J 2
(-4925 6650);
DISPLAY 0.489362 (-4925 6650);
PAINT SKYBLUE (-4925 6650);
DISPLAY INVISIBLE (-4925 6650);
FORCEADD OFFPAGE..2
(-5350 7150);
FORCEPROP 2 LAST $XR0 187 
J 0
(-5161 7150);
DISPLAY 0.638298 (-5161 7150);
PAINT MONO (-5161 7150);
FORCEPROP 2 LAST CDS_LIB standard
J 0
(-5350 7150);
DISPLAY INVISIBLE (-5350 7150);
FORCEPROP 1 LAST OFFPAGE TRUE
J 0
(-5025 7025);
DISPLAY 0.872340 (-5025 7025);
DISPLAY INVISIBLE (-5025 7025);
FORCEPROP 1 LAST COMMENT_BODY TRUE
J 0
(-5395 7055);
DISPLAY 0.872340 (-5395 7055);
PAINT GREEN (-5395 7055);
DISPLAY INVISIBLE (-5395 7055);
FORCEPROP 2 LAST PATH I109
J 0
(-5150 7200);
DISPLAY 0.680851 (-5150 7200);
DISPLAY INVISIBLE (-5150 7200);
FORCEADD UNIVERSAL_GND..1
(-4675 6600);
FORCEPROP 3 LASTPIN (-4675 6650) SIG_NAME GND\g
J 0
(-4665 6660);
DISPLAY 0.659574 (-4665 6660);
PAINT MONO (-4665 6660);
DISPLAY INVISIBLE (-4665 6660);
FORCEPROP 2 LAST CDS_LIB pure_quanta_power
J 0
(-4675 6600);
DISPLAY INVISIBLE (-4675 6600);
FORCEPROP 1 LAST HDL_POWER GND
J 1
(-4650 6525);
DISPLAY 0.872340 (-4650 6525);
PAINT GREEN (-4650 6525);
DISPLAY INVISIBLE (-4650 6525);
FORCEPROP 1 LAST PATH I110
J 0
(-4600 6600);
DISPLAY 0.872340 (-4600 6600);
PAINT AQUA (-4600 6600);
DISPLAY INVISIBLE (-4600 6600);
FORCEADD UNIVERSAL_GND..1
(-3250 3050);
FORCEPROP 3 LASTPIN (-3250 3100) SIG_NAME GND\g
J 0
(-3240 3110);
DISPLAY 0.659574 (-3240 3110);
PAINT MONO (-3240 3110);
DISPLAY INVISIBLE (-3240 3110);
FORCEPROP 2 LAST CDS_LIB pure_quanta_power
J 0
(-3250 3050);
DISPLAY INVISIBLE (-3250 3050);
FORCEPROP 1 LAST HDL_POWER GND
J 1
(-3225 2975);
DISPLAY 0.872340 (-3225 2975);
PAINT GREEN (-3225 2975);
DISPLAY INVISIBLE (-3225 2975);
FORCEPROP 1 LAST PATH I112
J 0
(-3175 3050);
DISPLAY 0.872340 (-3175 3050);
PAINT AQUA (-3175 3050);
DISPLAY INVISIBLE (-3175 3050);
FORCEADD Q_CAP..1
(-3250 3375);
FORCEPROP 1 LAST LOCATION C22
J 0
(-3200 3475);
DISPLAY 0.978723 (-3200 3475);
FORCEPROP 0 LAST $SEC 1
J 0
(-3200 3525);
DISPLAY 0.680851 (-3200 3525);
PAINT MONO (-3200 3525);
DISPLAY INVISIBLE (-3200 3525);
FORCEPROP 0 LAST CDS_SEC 1
J 0
(-3200 3525);
DISPLAY 0.680851 (-3200 3525);
DISPLAY INVISIBLE (-3200 3525);
FORCEPROP 1 LASTPIN (-3250 3475) $PN 1
J 0
(-3240 3455);
DISPLAY 0.787234 (-3240 3455);
PAINT MONO (-3240 3455);
FORCEPROP 1 LASTPIN (-3250 3275) $PN 2
J 0
(-3240 3255);
DISPLAY 0.787234 (-3240 3255);
PAINT MONO (-3240 3255);
FORCEPROP 1 LAST VOLTAGE 50V
J 0
(-3200 3375);
DISPLAY 0.978723 (-3200 3375);
FORCEPROP 1 LAST MATERIAL EMPTY
J 0
(-3200 3275);
DISPLAY 0.978723 (-3200 3275);
FORCEPROP 1 LAST TOLERANCE 10%
J 0
(-3200 3325);
DISPLAY 0.978723 (-3200 3325);
FORCEPROP 1 LAST PACK_TYPE C0402
J 0
(-3200 3175);
DISPLAY 0.978723 (-3200 3175);
FORCEPROP 1 LAST VALUE 0.01UF
J 0
(-3200 3425);
DISPLAY 0.978723 (-3200 3425);
FORCEPROP 2 LAST CDS_LIB pure_quanta
J 0
(-3250 3375);
DISPLAY INVISIBLE (-3250 3375);
FORCEPROP 1 LAST PATH I113
J 0
(-3200 3525);
DISPLAY 0.978723 (-3200 3525);
PAINT WHITE (-3200 3525);
DISPLAY INVISIBLE (-3200 3525);
FORCEPROP 1 LAST PART_NUMBER CH31006KB18
J 0
(-3200 3225);
DISPLAY 0.978723 (-3200 3225);
DISPLAY INVISIBLE (-3200 3225);
FORCEADD OFFPAGE..2
(-3350 3700);
FORCEPROP 2 LAST $XR0 187 
J 0
(-3161 3700);
DISPLAY 0.638298 (-3161 3700);
PAINT MONO (-3161 3700);
FORCEPROP 2 LAST CDS_LIB standard
J 0
(-3350 3700);
DISPLAY INVISIBLE (-3350 3700);
FORCEPROP 1 LAST OFFPAGE TRUE
J 0
(-3025 3575);
DISPLAY 0.872340 (-3025 3575);
DISPLAY INVISIBLE (-3025 3575);
FORCEPROP 1 LAST COMMENT_BODY TRUE
J 0
(-3395 3605);
DISPLAY 0.872340 (-3395 3605);
PAINT GREEN (-3395 3605);
DISPLAY INVISIBLE (-3395 3605);
FORCEPROP 2 LAST PATH I114
J 0
(-3150 3750);
DISPLAY 0.680851 (-3150 3750);
DISPLAY INVISIBLE (-3150 3750);
FORCEADD OFFPAGE..2
(-3525 6150);
FORCEPROP 2 LAST $XR0 187 
J 0
(-3336 6150);
DISPLAY 0.638298 (-3336 6150);
PAINT MONO (-3336 6150);
FORCEPROP 2 LAST CDS_LIB standard
J 0
(-3525 6150);
DISPLAY INVISIBLE (-3525 6150);
FORCEPROP 1 LAST OFFPAGE TRUE
J 0
(-3200 6025);
DISPLAY 0.872340 (-3200 6025);
DISPLAY INVISIBLE (-3200 6025);
FORCEPROP 1 LAST COMMENT_BODY TRUE
J 0
(-3570 6055);
DISPLAY 0.872340 (-3570 6055);
PAINT GREEN (-3570 6055);
DISPLAY INVISIBLE (-3570 6055);
FORCEPROP 2 LAST PATH I115
J 0
(-3325 6200);
DISPLAY 0.680851 (-3325 6200);
DISPLAY INVISIBLE (-3325 6200);
FORCEADD Q_RES..1
(-2975 5700);
FORCEPROP 1 LAST LOCATION R1779
J 0
(-3275 5700);
DISPLAY 0.489362 (-3275 5700);
PAINT SKYBLUE (-3275 5700);
FORCEPROP 0 LAST $SEC 1
J 0
(-2700 5750);
DISPLAY 0.680851 (-2700 5750);
PAINT MONO (-2700 5750);
DISPLAY INVISIBLE (-2700 5750);
FORCEPROP 0 LAST CDS_SEC 1
J 0
(-2700 5750);
DISPLAY 1.021277 (-2700 5750);
DISPLAY INVISIBLE (-2700 5750);
FORCEPROP 1 LASTPIN (-3075 5700) $PN 1
J 0
(-3063 5712);
DISPLAY 0.489362 (-3063 5712);
PAINT MONO (-3063 5712);
FORCEPROP 1 LASTPIN (-2875 5700) $PN 2
J 0
(-2913 5712);
DISPLAY 0.489362 (-2913 5712);
PAINT MONO (-2913 5712);
FORCEPROP 1 LAST TOLERANCE 1%
J 0
(-2775 5700);
DISPLAY 0.489362 (-2775 5700);
PAINT SKYBLUE (-2775 5700);
FORCEPROP 1 LAST MATERIAL CHIP
J 0
(-2700 5700);
DISPLAY 0.489362 (-2700 5700);
PAINT SKYBLUE (-2700 5700);
FORCEPROP 1 LAST VALUE 100
J 2
(-2800 5700);
DISPLAY 0.489362 (-2800 5700);
PAINT SKYBLUE (-2800 5700);
FORCEPROP 1 LAST WATTAGE 1/16W
J 2
(-2675 5625);
DISPLAY 0.489362 (-2675 5625);
PAINT SKYBLUE (-2675 5625);
FORCEPROP 1 LAST PACK_TYPE 0402LF
J 0
(-3050 5625);
DISPLAY 0.489362 (-3050 5625);
PAINT SKYBLUE (-3050 5625);
FORCEPROP 2 LAST CDS_LIB pure_quanta
J 0
(-2975 5700);
DISPLAY INVISIBLE (-2975 5700);
FORCEPROP 1 LAST PATH I116
J 0
(-3025 5850);
DISPLAY 0.978723 (-3025 5850);
PAINT WHITE (-3025 5850);
DISPLAY INVISIBLE (-3025 5850);
FORCEPROP 1 LAST PART_NUMBER CS11002FB07
J 0
(-3050 5575);
DISPLAY 0.489362 (-3050 5575);
PAINT SKYBLUE (-3050 5575);
DISPLAY INVISIBLE (-3050 5575);
FORCEADD UNIVERSAL_GND..1
(-3575 6400);
FORCEPROP 3 LASTPIN (-3575 6450) SIG_NAME GND\g
J 0
(-3565 6460);
DISPLAY 0.659574 (-3565 6460);
PAINT MONO (-3565 6460);
DISPLAY INVISIBLE (-3565 6460);
FORCEPROP 2 LAST CDS_LIB pure_quanta_power
J 0
(-3575 6400);
DISPLAY INVISIBLE (-3575 6400);
FORCEPROP 1 LAST HDL_POWER GND
J 1
(-3550 6325);
DISPLAY 0.872340 (-3550 6325);
PAINT GREEN (-3550 6325);
DISPLAY INVISIBLE (-3550 6325);
FORCEPROP 1 LAST PATH I117
J 0
(-3500 6400);
DISPLAY 0.872340 (-3500 6400);
PAINT AQUA (-3500 6400);
DISPLAY INVISIBLE (-3500 6400);
FORCEADD Q_CAP..1
(-3575 6775);
FORCEPROP 1 LAST LOCATION C1564
J 0
(-3525 6875);
DISPLAY 0.489362 (-3525 6875);
PAINT SKYBLUE (-3525 6875);
FORCEPROP 2 LAST $SEC 1
J 0
(-3525 6975);
DISPLAY 0.680851 (-3525 6975);
PAINT MONO (-3525 6975);
DISPLAY INVISIBLE (-3525 6975);
FORCEPROP 2 LAST CDS_SEC 1
J 0
(-3525 6975);
DISPLAY 0.680851 (-3525 6975);
DISPLAY INVISIBLE (-3525 6975);
FORCEPROP 1 LASTPIN (-3575 6875) $PN 1
J 0
(-3565 6855);
DISPLAY 0.489362 (-3565 6855);
FORCEPROP 1 LASTPIN (-3575 6675) $PN 2
J 0
(-3565 6655);
DISPLAY 0.489362 (-3565 6655);
FORCEPROP 1 LAST VALUE 1UF
J 0
(-3525 6825);
DISPLAY 0.489362 (-3525 6825);
PAINT SKYBLUE (-3525 6825);
FORCEPROP 1 LAST PACK_TYPE C0402
J 0
(-3525 6575);
DISPLAY 0.489362 (-3525 6575);
PAINT SKYBLUE (-3525 6575);
FORCEPROP 1 LAST TOLERANCE 10%
J 0
(-3525 6725);
DISPLAY 0.489362 (-3525 6725);
PAINT SKYBLUE (-3525 6725);
FORCEPROP 1 LAST MATERIAL X6S
J 0
(-3525 6675);
DISPLAY 0.489362 (-3525 6675);
PAINT SKYBLUE (-3525 6675);
FORCEPROP 1 LAST VOLTAGE 25V
J 0
(-3525 6775);
DISPLAY 0.489362 (-3525 6775);
PAINT SKYBLUE (-3525 6775);
FORCEPROP 2 LAST CDS_LIB pure_quanta
J 0
(-3575 6775);
DISPLAY INVISIBLE (-3575 6775);
FORCEPROP 1 LAST PATH I118
J 0
(-3525 6925);
DISPLAY 0.978723 (-3525 6925);
PAINT WHITE (-3525 6925);
DISPLAY INVISIBLE (-3525 6925);
FORCEPROP 1 LAST PART_NUMBER CH5104KEB02
J 0
(-3525 6625);
DISPLAY 0.489362 (-3525 6625);
PAINT SKYBLUE (-3525 6625);
DISPLAY INVISIBLE (-3525 6625);
FORCEADD OFFPAGE..1
R 2
(-3525 7200);
FORCEPROP 2 LAST $XR0 187 
J 0
(-3339 7200);
DISPLAY 0.638298 (-3339 7200);
PAINT MONO (-3339 7200);
FORCEPROP 2 LAST CDS_LIB standard
J 2
(-3525 7200);
DISPLAY INVISIBLE (-3525 7200);
FORCEPROP 1 LAST OFFPAGE TRUE
J 2
(-3850 7075);
DISPLAY 0.872340 (-3850 7075);
PAINT GREEN (-3850 7075);
DISPLAY INVISIBLE (-3850 7075);
FORCEPROP 1 LAST COMMENT_BODY TRUE
J 2
(-3650 7100);
DISPLAY 0.872340 (-3650 7100);
PAINT GREEN (-3650 7100);
DISPLAY INVISIBLE (-3650 7100);
FORCEPROP 2 LAST PATH I119
J 0
(-3325 7250);
DISPLAY 0.680851 (-3325 7250);
DISPLAY INVISIBLE (-3325 7250);
FORCEADD Q_RES..1
(-3075 7000);
FORCEPROP 1 LAST LOCATION R5053
J 0
(-3250 6950);
DISPLAY 0.638298 (-3250 6950);
FORCEPROP 0 LAST $SEC 1
J 0
(-2950 7000);
DISPLAY 0.680851 (-2950 7000);
PAINT MONO (-2950 7000);
DISPLAY INVISIBLE (-2950 7000);
FORCEPROP 0 LAST CDS_SEC 1
J 0
(-2950 7000);
DISPLAY 0.680851 (-2950 7000);
DISPLAY INVISIBLE (-2950 7000);
FORCEPROP 1 LASTPIN (-3175 7000) $PN 1
J 0
(-3163 7012);
DISPLAY 0.787234 (-3163 7012);
PAINT MONO (-3163 7012);
FORCEPROP 1 LASTPIN (-2975 7000) $PN 2
J 0
(-3013 7012);
DISPLAY 0.787234 (-3013 7012);
PAINT MONO (-3013 7012);
FORCEPROP 1 LAST MATERIAL EMPTY
J 0
(-3075 6850);
DISPLAY 0.638298 (-3075 6850);
PAINT RED (-3075 6850);
FORCEPROP 1 LAST TOLERANCE 1%
J 0
(-3050 6800);
DISPLAY 0.638298 (-3050 6800);
FORCEPROP 1 LAST PACK_TYPE 0402LF
J 0
(-3250 6800);
DISPLAY 0.638298 (-3250 6800);
FORCEPROP 1 LAST WATTAGE 1/16W
J 2
(-3100 6850);
DISPLAY 0.638298 (-3100 6850);
FORCEPROP 1 LAST VALUE 1K
J 2
(-2950 6950);
DISPLAY 0.638298 (-2950 6950);
FORCEPROP 2 LAST CDS_LIB pure_quanta
J 0
(-3075 7000);
DISPLAY INVISIBLE (-3075 7000);
FORCEPROP 1 LAST PATH I120
J 0
(-3125 7150);
DISPLAY 0.978723 (-3125 7150);
PAINT WHITE (-3125 7150);
DISPLAY INVISIBLE (-3125 7150);
FORCEPROP 1 LAST PART_NUMBER CS21002FB06
J 0
(-3250 6900);
DISPLAY 0.638298 (-3250 6900);
DISPLAY INVISIBLE (-3250 6900);
FORCEADD UNIVERSAL_POWER..1
(-2300 6800);
FORCEPROP 3 LASTPIN (-2300 6750) SIG_NAME P1V5_BAT\g
J 0
(-2290 6760);
DISPLAY 0.659574 (-2290 6760);
PAINT MONO (-2290 6760);
DISPLAY INVISIBLE (-2290 6760);
FORCEPROP 1 LAST HDL_POWER P1V5_BAT
J 1
(-2300 6850);
DISPLAY 0.489362 (-2300 6850);
PAINT GREEN (-2300 6850);
FORCEPROP 2 LAST CDS_LIB pure_quanta_power
J 0
(-2300 6800);
DISPLAY INVISIBLE (-2300 6800);
FORCEPROP 1 LAST PATH I121
J 0
(-2250 6825);
DISPLAY 0.872340 (-2250 6825);
PAINT AQUA (-2250 6825);
DISPLAY INVISIBLE (-2250 6825);
FORCEADD Q_RES..2
(-2750 7525);
FORCEPROP 1 LAST LOCATION R5054
J 0
(-2705 7650);
DISPLAY 0.638298 (-2705 7650);
FORCEPROP 0 LAST $SEC 1
J 0
(-2700 7700);
DISPLAY 0.680851 (-2700 7700);
PAINT MONO (-2700 7700);
DISPLAY INVISIBLE (-2700 7700);
FORCEPROP 0 LAST CDS_SEC 1
J 0
(-2700 7700);
DISPLAY 0.680851 (-2700 7700);
DISPLAY INVISIBLE (-2700 7700);
FORCEPROP 1 LASTPIN (-2750 7625) $PN 1
J 0
(-2745 7587);
DISPLAY 0.787234 (-2745 7587);
PAINT MONO (-2745 7587);
FORCEPROP 1 LASTPIN (-2750 7425) $PN 2
J 0
(-2745 7435);
DISPLAY 0.787234 (-2745 7435);
PAINT MONO (-2745 7435);
FORCEPROP 1 LAST TOLERANCE 5%
J 0
(-2705 7550);
DISPLAY 0.638298 (-2705 7550);
FORCEPROP 1 LAST VALUE 0
J 0
(-2705 7600);
DISPLAY 0.638298 (-2705 7600);
FORCEPROP 1 LAST PACK_TYPE 0402LF
J 0
(-2710 7350);
DISPLAY 0.638298 (-2710 7350);
FORCEPROP 1 LAST MATERIAL CHIP
J 0
(-2710 7450);
DISPLAY 0.638298 (-2710 7450);
FORCEPROP 1 LAST WATTAGE 1/16W
J 0
(-2710 7500);
DISPLAY 0.638298 (-2710 7500);
FORCEPROP 2 LAST CDS_LIB pure_quanta
J 0
(-2750 7525);
DISPLAY INVISIBLE (-2750 7525);
FORCEPROP 1 LAST PATH I122
J 0
(-2700 7700);
DISPLAY 0.978723 (-2700 7700);
PAINT WHITE (-2700 7700);
DISPLAY INVISIBLE (-2700 7700);
FORCEPROP 1 LAST PART_NUMBER CS00002JB13
J 0
(-2710 7400);
DISPLAY 0.638298 (-2710 7400);
DISPLAY INVISIBLE (-2710 7400);
FORCEADD UNIVERSAL_GND..1
(-2075 5925);
FORCEPROP 3 LASTPIN (-2075 5975) SIG_NAME GND\g
J 0
(-2065 5985);
DISPLAY 0.659574 (-2065 5985);
PAINT MONO (-2065 5985);
DISPLAY INVISIBLE (-2065 5985);
FORCEPROP 2 LAST CDS_LIB pure_quanta_power
J 0
(-2075 5925);
DISPLAY INVISIBLE (-2075 5925);
FORCEPROP 1 LAST HDL_POWER GND
J 1
(-2050 5850);
DISPLAY 0.872340 (-2050 5850);
PAINT GREEN (-2050 5850);
DISPLAY INVISIBLE (-2050 5850);
FORCEPROP 1 LAST PATH I123
J 0
(-2000 5925);
DISPLAY 0.872340 (-2000 5925);
PAINT AQUA (-2000 5925);
DISPLAY INVISIBLE (-2000 5925);
FORCEADD UNIVERSAL_GND..1
(-1650 5925);
FORCEPROP 3 LASTPIN (-1650 5975) SIG_NAME GND\g
J 0
(-1640 5985);
DISPLAY 0.659574 (-1640 5985);
PAINT MONO (-1640 5985);
DISPLAY INVISIBLE (-1640 5985);
FORCEPROP 2 LAST CDS_LIB pure_quanta_power
J 0
(-1650 5925);
DISPLAY INVISIBLE (-1650 5925);
FORCEPROP 1 LAST HDL_POWER GND
J 1
(-1625 5850);
DISPLAY 0.872340 (-1625 5850);
PAINT GREEN (-1625 5850);
DISPLAY INVISIBLE (-1625 5850);
FORCEPROP 1 LAST PATH I124
J 0
(-1575 5925);
DISPLAY 0.872340 (-1575 5925);
PAINT AQUA (-1575 5925);
DISPLAY INVISIBLE (-1575 5925);
FORCEADD Q_CAP..1
(-2075 6275);
FORCEPROP 1 LAST LOCATION C1567
J 0
(-2025 6375);
DISPLAY 0.489362 (-2025 6375);
PAINT SKYBLUE (-2025 6375);
FORCEPROP 0 LAST $SEC 1
J 0
(-2025 6425);
DISPLAY 0.680851 (-2025 6425);
PAINT MONO (-2025 6425);
DISPLAY INVISIBLE (-2025 6425);
FORCEPROP 0 LAST CDS_SEC 1
J 0
(-2025 6425);
DISPLAY 1.021277 (-2025 6425);
DISPLAY INVISIBLE (-2025 6425);
FORCEPROP 1 LASTPIN (-2075 6375) $PN 1
J 0
(-2065 6355);
DISPLAY 0.489362 (-2065 6355);
PAINT MONO (-2065 6355);
FORCEPROP 1 LASTPIN (-2075 6175) $PN 2
J 0
(-2065 6155);
DISPLAY 0.489362 (-2065 6155);
PAINT MONO (-2065 6155);
FORCEPROP 1 LAST VALUE 1UF
J 0
(-2025 6325);
DISPLAY 0.489362 (-2025 6325);
PAINT SKYBLUE (-2025 6325);
FORCEPROP 1 LAST MATERIAL X6S
J 0
(-2025 6175);
DISPLAY 0.489362 (-2025 6175);
PAINT SKYBLUE (-2025 6175);
FORCEPROP 1 LAST TOLERANCE 10%
J 0
(-2025 6225);
DISPLAY 0.489362 (-2025 6225);
PAINT SKYBLUE (-2025 6225);
FORCEPROP 1 LAST VOLTAGE 25V
J 0
(-2025 6275);
DISPLAY 0.489362 (-2025 6275);
PAINT SKYBLUE (-2025 6275);
FORCEPROP 1 LAST PACK_TYPE C0402
J 0
(-2025 6075);
DISPLAY 0.489362 (-2025 6075);
PAINT SKYBLUE (-2025 6075);
FORCEPROP 2 LAST CDS_LIB pure_quanta
J 0
(-2075 6275);
DISPLAY INVISIBLE (-2075 6275);
FORCEPROP 1 LAST PATH I125
J 0
(-2025 6425);
DISPLAY 0.978723 (-2025 6425);
PAINT WHITE (-2025 6425);
DISPLAY INVISIBLE (-2025 6425);
FORCEPROP 1 LAST PART_NUMBER CH5104KEB02
J 0
(-2025 6125);
DISPLAY 0.489362 (-2025 6125);
PAINT SKYBLUE (-2025 6125);
DISPLAY INVISIBLE (-2025 6125);
FORCEADD Q_CAP..1
(-1650 6275);
FORCEPROP 1 LAST LOCATION C5032
J 0
(-1600 6375);
DISPLAY 0.489362 (-1600 6375);
PAINT SKYBLUE (-1600 6375);
FORCEPROP 0 LAST $SEC 1
J 0
(-1600 6425);
DISPLAY 0.680851 (-1600 6425);
PAINT MONO (-1600 6425);
DISPLAY INVISIBLE (-1600 6425);
FORCEPROP 0 LAST CDS_SEC 1
J 0
(-1600 6425);
DISPLAY 1.021277 (-1600 6425);
DISPLAY INVISIBLE (-1600 6425);
FORCEPROP 1 LASTPIN (-1650 6375) $PN 1
J 0
(-1640 6355);
DISPLAY 0.489362 (-1640 6355);
PAINT MONO (-1640 6355);
FORCEPROP 1 LASTPIN (-1650 6175) $PN 2
J 0
(-1640 6155);
DISPLAY 0.489362 (-1640 6155);
PAINT MONO (-1640 6155);
FORCEPROP 1 LAST PACK_TYPE C0805
J 0
(-1600 6075);
DISPLAY 0.489362 (-1600 6075);
PAINT SKYBLUE (-1600 6075);
FORCEPROP 1 LAST VALUE 10UF
J 0
(-1600 6325);
DISPLAY 0.489362 (-1600 6325);
PAINT SKYBLUE (-1600 6325);
FORCEPROP 1 LAST VOLTAGE 25V
J 0
(-1600 6275);
DISPLAY 0.489362 (-1600 6275);
PAINT SKYBLUE (-1600 6275);
FORCEPROP 1 LAST TOLERANCE 10%
J 0
(-1600 6225);
DISPLAY 0.489362 (-1600 6225);
PAINT SKYBLUE (-1600 6225);
FORCEPROP 1 LAST MATERIAL X6S
J 0
(-1600 6175);
DISPLAY 0.489362 (-1600 6175);
PAINT SKYBLUE (-1600 6175);
FORCEPROP 2 LAST CDS_LIB pure_quanta
J 0
(-1650 6275);
DISPLAY INVISIBLE (-1650 6275);
FORCEPROP 1 LAST PATH I126
J 0
(-1600 6425);
DISPLAY 0.978723 (-1600 6425);
PAINT WHITE (-1600 6425);
DISPLAY INVISIBLE (-1600 6425);
FORCEPROP 1 LAST PART_NUMBER CH6104KEA00
J 0
(-1600 6125);
DISPLAY 0.489362 (-1600 6125);
PAINT SKYBLUE (-1600 6125);
DISPLAY INVISIBLE (-1600 6125);
FORCEADD UNIVERSAL_GND..1
R 2
(-1900 7325);
FORCEPROP 3 LASTPIN (-1900 7375) SIG_NAME GND\g
J 0
(-1890 7385);
DISPLAY 0.659574 (-1890 7385);
PAINT MONO (-1890 7385);
DISPLAY INVISIBLE (-1890 7385);
FORCEPROP 2 LAST CDS_LIB pure_quanta_power
J 2
(-1900 7325);
PAINT MONO (-1900 7325);
DISPLAY INVISIBLE (-1900 7325);
FORCEPROP 1 LAST HDL_POWER GND
J 1
(-1925 7250);
DISPLAY 0.872340 (-1925 7250);
PAINT GREEN (-1925 7250);
DISPLAY INVISIBLE (-1925 7250);
FORCEPROP 1 LAST PATH I127
J 2
(-1975 7325);
DISPLAY 0.872340 (-1975 7325);
PAINT AQUA (-1975 7325);
DISPLAY INVISIBLE (-1975 7325);
FORCEADD CONN3_210HP1030BR1..1
(-1600 7600);
FORCEPROP 1 LAST LOCATION JP12
J 0
(-1663 7829);
DISPLAY 0.723404 (-1663 7829);
PAINT GREEN (-1663 7829);
FORCEPROP 0 LAST $SEC 1
J 0
(-1650 7975);
DISPLAY 0.680851 (-1650 7975);
PAINT MONO (-1650 7975);
DISPLAY INVISIBLE (-1650 7975);
FORCEPROP 0 LAST CDS_SEC 1
J 0
(-1650 7975);
DISPLAY 0.680851 (-1650 7975);
DISPLAY INVISIBLE (-1650 7975);
FORCEPROP 0 LASTPIN (-1800 7650) $PN 1
J 2
(-1810 7660);
DISPLAY 0.680851 (-1810 7660);
PAINT MONO (-1810 7660);
FORCEPROP 0 LASTPIN (-1800 7600) $PN 2
J 2
(-1810 7610);
DISPLAY 0.680851 (-1810 7610);
PAINT MONO (-1810 7610);
FORCEPROP 0 LASTPIN (-1800 7550) $PN 3
J 2
(-1810 7560);
DISPLAY 0.680851 (-1810 7560);
PAINT MONO (-1810 7560);
FORCEPROP 1 LAST MATERIAL IO
J 0
(-1663 7724);
DISPLAY 0.723404 (-1663 7724);
PAINT GREEN (-1663 7724);
FORCEPROP 2 LAST VALUE CONN3_210-HP1-030BR1
J 0
(-1650 7875);
DISPLAY 0.680851 (-1650 7875);
FORCEPROP 2 LAST PART_TYPE THLF
J 0
(-1650 7925);
DISPLAY 0.680851 (-1650 7925);
FORCEPROP 1 LAST CDS_LMAN_SYM_OUTLINE -50,100,50,-100
J 0
(-1600 7600);
DISPLAY 0.468085 (-1600 7600);
PAINT GREEN (-1600 7600);
DISPLAY INVISIBLE (-1600 7600);
FORCEPROP 1 LAST NEEDS_NO_SIZE TRUE
J 0
(-1600 7600);
DISPLAY 0.723404 (-1600 7600);
PAINT GREEN (-1600 7600);
DISPLAY INVISIBLE (-1600 7600);
FORCEPROP 2 LAST CDS_LIB pure_quanta
J 0
(-1600 7600);
DISPLAY INVISIBLE (-1600 7600);
FORCEPROP 1 LAST PATH I128
J 0
(-1600 7600);
DISPLAY 0.723404 (-1600 7600);
PAINT GREEN (-1600 7600);
DISPLAY INVISIBLE (-1600 7600);
FORCEPROP 1 LAST PART_NUMBER DFHD03MS213
J 0
(-1663 7779);
DISPLAY 0.723404 (-1663 7779);
PAINT GREEN (-1663 7779);
DISPLAY INVISIBLE (-1663 7779);
FORCEADD Q_RES..2
(-4825 6350);
FORCEPROP 1 LAST LOCATION R1777
J 0
(-4780 6475);
DISPLAY 0.489362 (-4780 6475);
PAINT SKYBLUE (-4780 6475);
FORCEPROP 0 LAST $SEC 1
J 0
(-4775 6525);
DISPLAY 0.680851 (-4775 6525);
PAINT MONO (-4775 6525);
DISPLAY INVISIBLE (-4775 6525);
FORCEPROP 0 LAST CDS_SEC 1
J 0
(-4775 6525);
DISPLAY 1.021277 (-4775 6525);
DISPLAY INVISIBLE (-4775 6525);
FORCEPROP 1 LASTPIN (-4825 6450) $PN 1
J 0
(-4820 6412);
DISPLAY 0.489362 (-4820 6412);
PAINT MONO (-4820 6412);
FORCEPROP 1 LASTPIN (-4825 6250) $PN 2
J 0
(-4820 6260);
DISPLAY 0.489362 (-4820 6260);
PAINT MONO (-4820 6260);
FORCEPROP 1 LAST WATTAGE 1/16W
J 0
(-4785 6325);
DISPLAY 0.489362 (-4785 6325);
PAINT SKYBLUE (-4785 6325);
FORCEPROP 1 LAST TOLERANCE 1%
J 0
(-4780 6375);
DISPLAY 0.489362 (-4780 6375);
PAINT SKYBLUE (-4780 6375);
FORCEPROP 1 LAST VALUE 1K
J 0
(-4780 6425);
DISPLAY 0.489362 (-4780 6425);
PAINT SKYBLUE (-4780 6425);
FORCEPROP 1 LAST MATERIAL CHIP
J 0
(-4785 6275);
DISPLAY 0.489362 (-4785 6275);
PAINT SKYBLUE (-4785 6275);
FORCEPROP 1 LAST PACK_TYPE 0402LF
J 0
(-4785 6175);
DISPLAY 0.489362 (-4785 6175);
PAINT SKYBLUE (-4785 6175);
FORCEPROP 2 LAST CDS_LIB pure_quanta
J 0
(-4825 6350);
DISPLAY INVISIBLE (-4825 6350);
FORCEPROP 1 LAST PATH I129
J 0
(-4775 6525);
DISPLAY 0.978723 (-4775 6525);
PAINT WHITE (-4775 6525);
DISPLAY INVISIBLE (-4775 6525);
FORCEPROP 1 LAST PART_NUMBER CS21002FB06
J 0
(-4785 6225);
DISPLAY 0.489362 (-4785 6225);
PAINT SKYBLUE (-4785 6225);
DISPLAY INVISIBLE (-4785 6225);
FORCEADD NCP698SQ15T1G..1
(-4300 6925);
FORCEPROP 1 LAST LOCATION U167
J 0
(-4500 7160);
DISPLAY 0.723404 (-4500 7160);
PAINT GREEN (-4500 7160);
FORCEPROP 0 LAST $SEC 1
J 0
(-4500 7300);
DISPLAY 0.680851 (-4500 7300);
PAINT MONO (-4500 7300);
DISPLAY INVISIBLE (-4500 7300);
FORCEPROP 0 LAST CDS_SEC 1
J 0
(-4500 7300);
DISPLAY 0.680851 (-4500 7300);
DISPLAY INVISIBLE (-4500 7300);
FORCEPROP 0 LASTPIN (-3950 6850) $PN 4
J 0
(-3940 6860);
DISPLAY 0.680851 (-3940 6860);
PAINT MONO (-3940 6860);
FORCEPROP 0 LASTPIN (-4650 6850) $PN 1
J 2
(-4660 6860);
DISPLAY 0.680851 (-4660 6860);
PAINT MONO (-4660 6860);
FORCEPROP 0 LASTPIN (-4650 7000) $PN 2
J 2
(-4660 7010);
DISPLAY 0.680851 (-4660 7010);
PAINT MONO (-4660 7010);
FORCEPROP 0 LASTPIN (-3950 7000) $PN 3
J 0
(-3940 7010);
DISPLAY 0.680851 (-3940 7010);
PAINT MONO (-3940 7010);
FORCEPROP 1 LAST MATERIAL EMPTY
J 0
(-4500 7060);
DISPLAY 0.723404 (-4500 7060);
PAINT RED (-4500 7060);
FORCEPROP 2 LAST VALUE NCP698SQ15T1G
J 0
(-4500 7200);
DISPLAY 0.680851 (-4500 7200);
FORCEPROP 2 LAST PART_TYPE SMLF
J 0
(-4500 7250);
DISPLAY 0.680851 (-4500 7250);
FORCEPROP 1 LAST CDS_LMAN_SYM_OUTLINE -200,125,200,-125
J 0
(-4300 6925);
DISPLAY 0.468085 (-4300 6925);
PAINT GREEN (-4300 6925);
DISPLAY INVISIBLE (-4300 6925);
FORCEPROP 1 LAST NEEDS_NO_SIZE TRUE
J 0
(-4300 6925);
DISPLAY 0.723404 (-4300 6925);
PAINT GREEN (-4300 6925);
DISPLAY INVISIBLE (-4300 6925);
FORCEPROP 2 LAST CDS_LIB pure_quanta
J 0
(-4300 6925);
DISPLAY INVISIBLE (-4300 6925);
FORCEPROP 1 LAST PATH I130
J 0
(-4300 6925);
DISPLAY 0.723404 (-4300 6925);
PAINT GREEN (-4300 6925);
DISPLAY INVISIBLE (-4300 6925);
FORCEPROP 1 LAST PART_NUMBER AL000698000
J 0
(-4500 7109);
DISPLAY 0.723404 (-4500 7109);
PAINT GREEN (-4500 7109);
DISPLAY INVISIBLE (-4500 7109);
FORCEADD Q_RES..1
(-8175 6950);
FORCEPROP 1 LAST LOCATION R1775
J 0
(-8475 6950);
DISPLAY 0.787234 (-8475 6950);
FORCEPROP 0 LAST $SEC 1
J 0
(-7950 7000);
DISPLAY 0.680851 (-7950 7000);
PAINT MONO (-7950 7000);
DISPLAY INVISIBLE (-7950 7000);
FORCEPROP 0 LAST CDS_SEC 1
J 0
(-7950 7000);
DISPLAY 0.680851 (-7950 7000);
DISPLAY INVISIBLE (-7950 7000);
FORCEPROP 1 LASTPIN (-8275 6950) $PN 1
J 0
(-8263 6962);
DISPLAY 0.787234 (-8263 6962);
PAINT MONO (-8263 6962);
FORCEPROP 1 LASTPIN (-8075 6950) $PN 2
J 0
(-8113 6962);
DISPLAY 0.787234 (-8113 6962);
PAINT MONO (-8113 6962);
FORCEPROP 1 LAST VALUE 1K
J 2
(-7950 6950);
DISPLAY 0.638298 (-7950 6950);
FORCEPROP 1 LAST PACK_TYPE 0402LF
J 0
(-8125 6800);
DISPLAY 0.638298 (-8125 6800);
FORCEPROP 1 LAST WATTAGE 1/16W
J 2
(-8000 6850);
DISPLAY 0.638298 (-8000 6850);
FORCEPROP 1 LAST TOLERANCE 1%
J 0
(-8250 6800);
DISPLAY 0.638298 (-8250 6800);
FORCEPROP 1 LAST MATERIAL CHIP
J 0
(-8375 6850);
DISPLAY 0.638298 (-8375 6850);
FORCEPROP 2 LAST CDS_LIB pure_quanta
J 0
(-8175 6950);
DISPLAY INVISIBLE (-8175 6950);
FORCEPROP 1 LAST PATH I131
J 0
(-8225 7100);
DISPLAY 0.978723 (-8225 7100);
PAINT WHITE (-8225 7100);
DISPLAY INVISIBLE (-8225 7100);
FORCEPROP 1 LAST PART_NUMBER CS21002FB06
J 0
(-8350 6900);
DISPLAY 0.638298 (-8350 6900);
DISPLAY INVISIBLE (-8350 6900);
FORCEADD GND..1
(-9400 6450);
FORCEPROP 3 LASTPIN (-9400 6500) SIG_NAME GND\g
J 0
(-9390 6510);
DISPLAY 0.659574 (-9390 6510);
PAINT MONO (-9390 6510);
DISPLAY INVISIBLE (-9390 6510);
FORCEPROP 1 LAST SIZE 1B
J 0
(-9325 6400);
DISPLAY 1.170213 (-9325 6400);
PAINT AQUA (-9325 6400);
DISPLAY INVISIBLE (-9325 6400);
FORCEPROP 2 LAST CDS_LIB pure_quanta_power
J 0
(-9400 6450);
DISPLAY INVISIBLE (-9400 6450);
FORCEPROP 1 LAST HDL_POWER GND
J 0
(-9400 6600);
DISPLAY 1.170213 (-9400 6600);
PAINT GREEN (-9400 6600);
DISPLAY INVISIBLE (-9400 6600);
FORCEPROP 1 LAST PATH I85
J 0
(-9325 6450);
DISPLAY 0.872340 (-9325 6450);
PAINT AQUA (-9325 6450);
DISPLAY INVISIBLE (-9325 6450);
FORCEADD CONN2_AAABAT029Y19..1
R 2
(-9125 6950);
FORCEPROP 1 LAST LOCATION BT2
J 2
(-9081 7281);
DISPLAY 0.723404 (-9081 7281);
PAINT GREEN (-9081 7281);
FORCEPROP 0 LAST $SEC 1
J 0
(-9075 7325);
DISPLAY 0.680851 (-9075 7325);
PAINT MONO (-9075 7325);
DISPLAY INVISIBLE (-9075 7325);
FORCEPROP 0 LAST CDS_SEC 1
J 2
(-9075 7325);
DISPLAY 1.021277 (-9075 7325);
DISPLAY INVISIBLE (-9075 7325);
FORCEPROP 0 LASTPIN (-8925 6950) $PN 1
J 0
(-8915 6960);
DISPLAY 0.680851 (-8915 6960);
PAINT MONO (-8915 6960);
FORCEPROP 0 LASTPIN (-9325 6950) $PN 2
J 2
(-9335 6960);
DISPLAY 0.680851 (-9335 6960);
PAINT MONO (-9335 6960);
FORCEPROP 2 LAST VALUE CONN2_AAA-BAT-029-Y19
J 2
(-9025 7125);
DISPLAY 0.489362 (-9025 7125);
PAINT SKYBLUE (-9025 7125);
FORCEPROP 1 LAST MATERIAL IO
J 2
(-9081 7007);
DISPLAY 0.723404 (-9081 7007);
PAINT GREEN (-9081 7007);
FORCEPROP 2 LAST PART_TYPE THLF
J 2
(-9050 7175);
DISPLAY 1.021277 (-9050 7175);
FORCEPROP 1 LAST CDS_LMAN_SYM_OUTLINE -50,50,50,-50
J 2
(-9125 6950);
DISPLAY 0.468085 (-9125 6950);
PAINT GREEN (-9125 6950);
DISPLAY INVISIBLE (-9125 6950);
FORCEPROP 1 LAST NEEDS_NO_SIZE TRUE
J 2
(-9125 6950);
DISPLAY 0.723404 (-9125 6950);
PAINT GREEN (-9125 6950);
DISPLAY INVISIBLE (-9125 6950);
FORCEPROP 2 LAST CDS_LIB pure_quanta
J 0
(-9125 6950);
DISPLAY INVISIBLE (-9125 6950);
FORCEPROP 1 LAST PATH I86
J 2
(-9125 6950);
DISPLAY 0.723404 (-9125 6950);
PAINT GREEN (-9125 6950);
DISPLAY INVISIBLE (-9125 6950);
FORCEPROP 1 LAST PART_NUMBER DFHS02FR062
J 2
(-9050 7075);
DISPLAY 0.723404 (-9050 7075);
PAINT GREEN (-9050 7075);
DISPLAY INVISIBLE (-9050 7075);
FORCEADD UNIVERSAL_POWER..1
(-8525 7400);
FORCEPROP 3 LASTPIN (-8525 7350) SIG_NAME P3V3_AUX\g
J 0
(-8515 7360);
DISPLAY 0.659574 (-8515 7360);
PAINT MONO (-8515 7360);
DISPLAY INVISIBLE (-8515 7360);
FORCEPROP 1 LAST HDL_POWER P3V3_AUX
J 1
(-8525 7450);
DISPLAY 0.489362 (-8525 7450);
PAINT GREEN (-8525 7450);
FORCEPROP 2 LAST CDS_LIB pure_quanta_power
J 0
(-8525 7400);
DISPLAY INVISIBLE (-8525 7400);
FORCEPROP 1 LAST PATH I87
J 0
(-8475 7425);
DISPLAY 0.872340 (-8475 7425);
PAINT AQUA (-8475 7425);
DISPLAY INVISIBLE (-8475 7425);
FORCEADD OFFPAGE..1
(-6075 3650);
FORCEPROP 2 LAST $XR0 187 
J 0
(-6327 3650);
DISPLAY 0.638298 (-6327 3650);
PAINT MONO (-6327 3650);
FORCEPROP 2 LAST CDS_LIB standard
J 0
(-6075 3650);
DISPLAY INVISIBLE (-6075 3650);
FORCEPROP 1 LAST OFFPAGE TRUE
J 0
(-5750 3525);
DISPLAY 0.872340 (-5750 3525);
PAINT GREEN (-5750 3525);
DISPLAY INVISIBLE (-5750 3525);
FORCEPROP 1 LAST COMMENT_BODY TRUE
J 0
(-5950 3550);
DISPLAY 0.872340 (-5950 3550);
PAINT GREEN (-5950 3550);
DISPLAY INVISIBLE (-5950 3550);
FORCEPROP 2 LAST PATH I88
J 0
(-6350 3700);
DISPLAY 0.680851 (-6350 3700);
DISPLAY INVISIBLE (-6350 3700);
FORCEADD OFFPAGE..1
(-6075 3750);
FORCEPROP 2 LAST $XR0 187 
J 0
(-6327 3750);
DISPLAY 0.638298 (-6327 3750);
PAINT MONO (-6327 3750);
FORCEPROP 2 LAST CDS_LIB standard
J 0
(-6075 3750);
DISPLAY INVISIBLE (-6075 3750);
FORCEPROP 1 LAST OFFPAGE TRUE
J 0
(-5750 3625);
DISPLAY 0.872340 (-5750 3625);
PAINT GREEN (-5750 3625);
DISPLAY INVISIBLE (-5750 3625);
FORCEPROP 1 LAST COMMENT_BODY TRUE
J 0
(-5950 3650);
DISPLAY 0.872340 (-5950 3650);
PAINT GREEN (-5950 3650);
DISPLAY INVISIBLE (-5950 3650);
FORCEPROP 2 LAST PATH I89
J 0
(-6350 3800);
DISPLAY 0.680851 (-6350 3800);
DISPLAY INVISIBLE (-6350 3800);
FORCEADD UNIVERSAL_GND..1
(-5375 3450);
FORCEPROP 3 LASTPIN (-5375 3500) SIG_NAME GND\g
J 0
(-5365 3510);
DISPLAY 0.659574 (-5365 3510);
PAINT MONO (-5365 3510);
DISPLAY INVISIBLE (-5365 3510);
FORCEPROP 2 LAST CDS_LIB pure_quanta_power
J 0
(-5375 3450);
DISPLAY INVISIBLE (-5375 3450);
FORCEPROP 1 LAST HDL_POWER GND
J 1
(-5350 3375);
DISPLAY 0.872340 (-5350 3375);
PAINT GREEN (-5350 3375);
DISPLAY INVISIBLE (-5350 3375);
FORCEPROP 1 LAST PATH I90
J 0
(-5300 3450);
DISPLAY 0.872340 (-5300 3450);
PAINT AQUA (-5300 3450);
DISPLAY INVISIBLE (-5300 3450);
FORCEADD TPS71715DCKR..1
(-4725 3650);
FORCEPROP 1 LAST LOCATION U9
J 0
(-4972 4089);
DISPLAY 0.723404 (-4972 4089);
PAINT GREEN (-4972 4089);
FORCEPROP 2 LAST SEC 1
J 0
(-4950 4225);
DISPLAY 0.680851 (-4950 4225);
PAINT MONO (-4950 4225);
DISPLAY INVISIBLE (-4950 4225);
FORCEPROP 2 LASTPIN (-5125 3650) $PN 3
J 2
(-5135 3660);
DISPLAY 0.680851 (-5135 3660);
PAINT MONO (-5135 3660);
FORCEPROP 2 LASTPIN (-5125 3550) $PN 2
J 2
(-5135 3560);
DISPLAY 0.680851 (-5135 3560);
PAINT MONO (-5135 3560);
FORCEPROP 2 LASTPIN (-5125 3750) $PN 1
J 2
(-5135 3760);
DISPLAY 0.680851 (-5135 3760);
PAINT MONO (-5135 3760);
FORCEPROP 2 LASTPIN (-4325 3600) $PN 4
J 0
(-4315 3610);
DISPLAY 0.680851 (-4315 3610);
PAINT MONO (-4315 3610);
FORCEPROP 2 LASTPIN (-4325 3700) $PN 5
J 0
(-4315 3710);
DISPLAY 0.680851 (-4315 3710);
PAINT MONO (-4315 3710);
FORCEPROP 1 LAST MATERIAL EMPTY
J 0
(-4972 3815);
DISPLAY 0.723404 (-4972 3815);
PAINT GREEN (-4972 3815);
FORCEPROP 2 LAST PART_TYPE SMLF
J 0
(-4950 4175);
DISPLAY 0.680851 (-4950 4175);
FORCEPROP 2 LAST VALUE TPS71715DCKR
J 0
(-4950 4125);
DISPLAY 0.680851 (-4950 4125);
FORCEPROP 2 LAST SEC_TYPE 
J 0
(-4950 4225);
DISPLAY 0.680851 (-4950 4225);
DISPLAY INVISIBLE (-4950 4225);
FORCEPROP 1 LAST CDS_LMAN_SYM_OUTLINE -250,150,250,-150
J 0
(-4725 3650);
DISPLAY 0.468085 (-4725 3650);
PAINT GREEN (-4725 3650);
DISPLAY INVISIBLE (-4725 3650);
FORCEPROP 1 LAST NEEDS_NO_SIZE TRUE
J 0
(-4725 3650);
DISPLAY 0.723404 (-4725 3650);
PAINT GREEN (-4725 3650);
DISPLAY INVISIBLE (-4725 3650);
FORCEPROP 2 LAST CDS_LIB pure_quanta
J 0
(-4725 3650);
DISPLAY INVISIBLE (-4725 3650);
FORCEPROP 1 LAST PATH I91
J 0
(-4725 3650);
DISPLAY 0.723404 (-4725 3650);
PAINT GREEN (-4725 3650);
DISPLAY INVISIBLE (-4725 3650);
FORCEPROP 1 LAST PART_NUMBER AL071715001
J 0
(-4972 3942);
DISPLAY 0.723404 (-4972 3942);
PAINT GREEN (-4972 3942);
DISPLAY INVISIBLE (-4972 3942);
FORCEADD OFFPAGE..1
(-7100 5025);
FORCEPROP 2 LAST $XR0 82 
J 0
(-7351 5025);
DISPLAY 0.638298 (-7351 5025);
PAINT MONO (-7351 5025);
FORCEPROP 2 LAST CDS_LIB standard
J 0
(-7100 5025);
DISPLAY INVISIBLE (-7100 5025);
FORCEPROP 1 LAST OFFPAGE TRUE
J 0
(-6775 4900);
DISPLAY 0.872340 (-6775 4900);
PAINT GREEN (-6775 4900);
DISPLAY INVISIBLE (-6775 4900);
FORCEPROP 1 LAST COMMENT_BODY TRUE
J 0
(-6975 4925);
DISPLAY 0.872340 (-6975 4925);
PAINT GREEN (-6975 4925);
DISPLAY INVISIBLE (-6975 4925);
FORCEPROP 2 LAST PATH I92
J 0
(-7350 5075);
DISPLAY 0.680851 (-7350 5075);
DISPLAY INVISIBLE (-7350 5075);
FORCEADD UNIVERSAL_GND..1
(-6250 4350);
FORCEPROP 3 LASTPIN (-6250 4400) SIG_NAME GND\g
J 0
(-6240 4410);
DISPLAY 0.659574 (-6240 4410);
PAINT MONO (-6240 4410);
DISPLAY INVISIBLE (-6240 4410);
FORCEPROP 2 LAST CDS_LIB pure_quanta_power
J 0
(-6250 4350);
DISPLAY INVISIBLE (-6250 4350);
FORCEPROP 1 LAST HDL_POWER GND
J 1
(-6225 4275);
DISPLAY 0.872340 (-6225 4275);
PAINT GREEN (-6225 4275);
DISPLAY INVISIBLE (-6225 4275);
FORCEPROP 1 LAST PATH I93
J 0
(-6175 4350);
DISPLAY 0.872340 (-6175 4350);
PAINT AQUA (-6175 4350);
DISPLAY INVISIBLE (-6175 4350);
FORCEADD Q_RES..2
(-6700 4825);
FORCEPROP 1 LAST LOCATION R1776
J 0
(-6655 4950);
DISPLAY 0.489362 (-6655 4950);
PAINT SKYBLUE (-6655 4950);
FORCEPROP 0 LAST $SEC 1
J 0
(-6650 5000);
DISPLAY 0.680851 (-6650 5000);
PAINT MONO (-6650 5000);
DISPLAY INVISIBLE (-6650 5000);
FORCEPROP 0 LAST CDS_SEC 1
J 0
(-6650 5000);
DISPLAY 1.021277 (-6650 5000);
DISPLAY INVISIBLE (-6650 5000);
FORCEPROP 1 LASTPIN (-6700 4925) $PN 1
J 0
(-6695 4887);
DISPLAY 0.489362 (-6695 4887);
PAINT MONO (-6695 4887);
FORCEPROP 1 LASTPIN (-6700 4725) $PN 2
J 0
(-6695 4735);
DISPLAY 0.489362 (-6695 4735);
PAINT MONO (-6695 4735);
FORCEPROP 1 LAST PACK_TYPE 0402LF
J 0
(-6660 4650);
DISPLAY 0.489362 (-6660 4650);
PAINT SKYBLUE (-6660 4650);
FORCEPROP 1 LAST WATTAGE 1/16W
J 0
(-6660 4800);
DISPLAY 0.489362 (-6660 4800);
PAINT SKYBLUE (-6660 4800);
FORCEPROP 1 LAST TOLERANCE 1%
J 0
(-6655 4850);
DISPLAY 0.489362 (-6655 4850);
PAINT SKYBLUE (-6655 4850);
FORCEPROP 1 LAST MATERIAL CHIP
J 0
(-6660 4750);
DISPLAY 0.489362 (-6660 4750);
PAINT SKYBLUE (-6660 4750);
FORCEPROP 1 LAST VALUE 1K
J 0
(-6655 4900);
DISPLAY 0.489362 (-6655 4900);
PAINT SKYBLUE (-6655 4900);
FORCEPROP 2 LAST CDS_LIB pure_quanta
J 0
(-6700 4825);
DISPLAY INVISIBLE (-6700 4825);
FORCEPROP 2 LAST BOM_COST VR_SYSTEM 
J 0
(-6650 5000);
DISPLAY 0.680851 (-6650 5000);
DISPLAY INVISIBLE (-6650 5000);
FORCEPROP 1 LAST PATH I94
J 0
(-6650 5000);
DISPLAY 0.978723 (-6650 5000);
PAINT WHITE (-6650 5000);
DISPLAY INVISIBLE (-6650 5000);
FORCEPROP 1 LAST PART_NUMBER CS21002FB06
J 0
(-6660 4700);
DISPLAY 0.489362 (-6660 4700);
PAINT SKYBLUE (-6660 4700);
DISPLAY INVISIBLE (-6660 4700);
FORCEADD Q_CAP..1
(-6250 4825);
FORCEPROP 1 LAST LOCATION C1563
J 0
(-6200 4950);
DISPLAY 0.489362 (-6200 4950);
PAINT SKYBLUE (-6200 4950);
FORCEPROP 2 LAST $SEC 1
J 0
(-6200 5025);
DISPLAY 0.680851 (-6200 5025);
PAINT MONO (-6200 5025);
DISPLAY INVISIBLE (-6200 5025);
FORCEPROP 2 LAST CDS_SEC 1
J 0
(-6200 5025);
DISPLAY 0.680851 (-6200 5025);
DISPLAY INVISIBLE (-6200 5025);
FORCEPROP 1 LASTPIN (-6250 4925) $PN 1
J 0
(-6240 4905);
DISPLAY 0.489362 (-6240 4905);
FORCEPROP 1 LASTPIN (-6250 4725) $PN 2
J 0
(-6240 4705);
DISPLAY 0.489362 (-6240 4705);
FORCEPROP 1 LAST TOLERANCE 10%
J 0
(-6200 4800);
DISPLAY 0.489362 (-6200 4800);
PAINT SKYBLUE (-6200 4800);
FORCEPROP 1 LAST VOLTAGE 16V
J 0
(-6200 4850);
DISPLAY 0.489362 (-6200 4850);
PAINT SKYBLUE (-6200 4850);
FORCEPROP 1 LAST MATERIAL X7R
J 0
(-6200 4750);
DISPLAY 0.489362 (-6200 4750);
PAINT SKYBLUE (-6200 4750);
FORCEPROP 1 LAST VALUE 0.1UF
J 0
(-6200 4900);
DISPLAY 0.489362 (-6200 4900);
PAINT SKYBLUE (-6200 4900);
FORCEPROP 1 LAST PACK_TYPE C0402
J 0
(-6200 4650);
DISPLAY 0.489362 (-6200 4650);
PAINT SKYBLUE (-6200 4650);
FORCEPROP 2 LAST CDS_LIB pure_quanta
J 0
(-6250 4825);
DISPLAY INVISIBLE (-6250 4825);
FORCEPROP 1 LAST PATH I95
J 0
(-6200 4975);
DISPLAY 0.978723 (-6200 4975);
PAINT WHITE (-6200 4975);
DISPLAY INVISIBLE (-6200 4975);
FORCEPROP 1 LAST PART_NUMBER CH4103K1B08
J 0
(-6200 4700);
DISPLAY 0.489362 (-6200 4700);
PAINT SKYBLUE (-6200 4700);
DISPLAY INVISIBLE (-6200 4700);
FORCEADD Q_RES..1
(-8175 7050);
FORCEPROP 1 LAST LOCATION R5101
J 0
(-8500 7075);
DISPLAY 0.638298 (-8500 7075);
FORCEPROP 0 LAST $SEC 1
J 0
(-8300 7275);
DISPLAY 0.680851 (-8300 7275);
PAINT MONO (-8300 7275);
DISPLAY INVISIBLE (-8300 7275);
FORCEPROP 0 LAST CDS_SEC 1
J 0
(-8300 7275);
DISPLAY 0.680851 (-8300 7275);
DISPLAY INVISIBLE (-8300 7275);
FORCEPROP 1 LASTPIN (-8275 7050) $PN 1
J 0
(-8263 7062);
DISPLAY 0.787234 (-8263 7062);
PAINT MONO (-8263 7062);
FORCEPROP 1 LASTPIN (-8075 7050) $PN 2
J 0
(-8113 7062);
DISPLAY 0.787234 (-8113 7062);
PAINT MONO (-8113 7062);
FORCEPROP 1 LAST PACK_TYPE 0402LF
J 0
(-8300 7175);
DISPLAY 0.638298 (-8300 7175);
FORCEPROP 1 LAST MATERIAL CHIP
J 0
(-8350 7075);
DISPLAY 0.638298 (-8350 7075);
FORCEPROP 1 LAST WATTAGE 1/16W
J 2
(-7825 7175);
DISPLAY 0.638298 (-7825 7175);
FORCEPROP 1 LAST TOLERANCE 5%
J 0
(-8075 7175);
DISPLAY 0.638298 (-8075 7175);
FORCEPROP 1 LAST VALUE 10K
J 2
(-8025 7075);
DISPLAY 0.638298 (-8025 7075);
FORCEPROP 2 LAST CDS_LIB pure_quanta
J 0
(-8175 7050);
DISPLAY INVISIBLE (-8175 7050);
FORCEPROP 1 LAST PATH I97
J 0
(-8225 7200);
DISPLAY 0.978723 (-8225 7200);
PAINT WHITE (-8225 7200);
DISPLAY INVISIBLE (-8225 7200);
FORCEPROP 1 LAST PART_NUMBER CS31002JB08
J 0
(-8300 7225);
DISPLAY 0.638298 (-8300 7225);
DISPLAY INVISIBLE (-8300 7225);
FORCEADD OFFPAGE..2
(-7425 6750);
FORCEPROP 2 LAST CDS_LIB standard
J 0
(-7425 6750);
DISPLAY INVISIBLE (-7425 6750);
FORCEPROP 2 LAST $XRERR UNIQUE?
J 0
(-7236 6750);
DISPLAY 0.638298 (-7236 6750);
PAINT MONO (-7236 6750);
DISPLAY INVISIBLE (-7236 6750);
FORCEPROP 1 LAST OFFPAGE TRUE
J 0
(-7100 6625);
DISPLAY 0.872340 (-7100 6625);
DISPLAY INVISIBLE (-7100 6625);
FORCEPROP 1 LAST COMMENT_BODY TRUE
J 0
(-7470 6655);
DISPLAY 0.872340 (-7470 6655);
PAINT GREEN (-7470 6655);
DISPLAY INVISIBLE (-7470 6655);
FORCEPROP 2 LAST PATH I98
J 0
(-7250 6825);
DISPLAY 0.680851 (-7250 6825);
DISPLAY INVISIBLE (-7250 6825);
FORCEADD SCHOTTKY_DUAL_12A_3C..1
R 5
(-7200 7000);
FORCEPROP 1 LAST LOCATION U166
J 0
(-7175 7350);
DISPLAY 0.489362 (-7175 7350);
PAINT SKYBLUE (-7175 7350);
FORCEPROP 0 LAST $SEC 1
J 0
(-7175 7400);
DISPLAY 0.680851 (-7175 7400);
PAINT MONO (-7175 7400);
DISPLAY INVISIBLE (-7175 7400);
FORCEPROP 0 LAST CDS_SEC 1
J 0
(-7175 7400);
DISPLAY 1.021277 (-7175 7400);
DISPLAY INVISIBLE (-7175 7400);
FORCEPROP 0 LASTPIN (-7300 6950) $PN 2
J 2
(-7310 6960);
DISPLAY 0.489362 (-7310 6960);
PAINT MONO (-7310 6960);
FORCEPROP 0 LASTPIN (-7300 7050) $PN 1
J 2
(-7310 7060);
DISPLAY 0.489362 (-7310 7060);
PAINT MONO (-7310 7060);
FORCEPROP 0 LASTPIN (-7100 7000) $PN 3
J 0
(-7090 7010);
DISPLAY 0.489362 (-7090 7010);
PAINT MONO (-7090 7010);
FORCEPROP 1 LAST MATERIAL IC
J 0
(-7175 7125);
DISPLAY 0.489362 (-7175 7125);
PAINT SKYBLUE (-7175 7125);
FORCEPROP 2 LAST VALUE BAT54CW
J 0
(-7175 7225);
DISPLAY 0.489362 (-7175 7225);
PAINT SKYBLUE (-7175 7225);
FORCEPROP 2 LAST PART_TYPE SMLF
J 0
(-7175 7275);
DISPLAY 1.021277 (-7175 7275);
FORCEPROP 2 LAST CDS_LIB pure_quanta
R 3
J 0
(-7200 7000);
DISPLAY INVISIBLE (-7200 7000);
FORCEPROP 1 LAST NEEDS_NO_SIZE TRUE
R 3
J 0
(-7210 6900);
DISPLAY 0.723404 (-7210 6900);
PAINT GREEN (-7210 6900);
DISPLAY INVISIBLE (-7210 6900);
FORCEPROP 1 LAST CDS_LMAN_SYM_OUTLINE -100,50,100,-50
R 3
J 0
(-7200 7000);
DISPLAY 0.468085 (-7200 7000);
PAINT GREEN (-7200 7000);
DISPLAY INVISIBLE (-7200 7000);
FORCEPROP 1 LAST PATH I99
R 3
J 0
(-7250 6900);
DISPLAY 0.723404 (-7250 6900);
PAINT GREEN (-7250 6900);
DISPLAY INVISIBLE (-7250 6900);
FORCEPROP 1 LAST PART_NUMBER BCBAT54CZ13
J 0
(-7175 7175);
DISPLAY 0.489362 (-7175 7175);
PAINT SKYBLUE (-7175 7175);
DISPLAY INVISIBLE (-7175 7175);
FORCEADD DNS..1
(-4275 7100);
PAINT RED (-4275 7100);
FORCEPROP 2 LAST CDS_LIB mstr_misc
J 0
(-4275 7100);
DISPLAY INVISIBLE (-4275 7100);
FORCEPROP 1 LAST COMMENT_BODY TRUE
R 1
J 0
(-4200 6875);
DISPLAY 0.872340 (-4200 6875);
PAINT GREEN (-4200 6875);
DISPLAY INVISIBLE (-4200 6875);
FORCEADD DNS..1
(-3075 6975);
PAINT RED (-3075 6975);
FORCEPROP 2 LAST CDS_LIB mstr_misc
J 0
(-3075 6975);
DISPLAY INVISIBLE (-3075 6975);
FORCEPROP 1 LAST COMMENT_BODY TRUE
R 1
J 0
(-3000 6750);
DISPLAY 0.872340 (-3000 6750);
PAINT GREEN (-3000 6750);
DISPLAY INVISIBLE (-3000 6750);
FORCEADD QUANTA_TITLE_BLOCK_C..1
(-200 1950);
FORCEPROP 0 LAST CDS_CON_LAST_MODIFIED Thu Sep 14 16:13:03 2023
J 0
(-2085 1965);
DISPLAY INVISIBLE (-2085 1965);
FORCEPROP 1 LAST CUSTOM_TXT_CDS <CON_LAST_MODIFIED>
J 0
(-2085 1965);
DISPLAY 0.978723 (-2085 1965);
FORCEPROP 2 LAST CUSTOM_TXT_CDS <XR_PAGE_TITLE>
J 0
(-8090 7200);
DISPLAY 0.638298 (-8090 7200);
PAINT PINK (-8090 7200);
DISPLAY INVISIBLE (-8090 7200);
FORCEPROP 1 LAST CUSTOM_TXT_CDS <NAME_2>
J 0
(-3375 2000);
FORCEPROP 1 LAST CUSTOM_TXT_CDS <NAME_1>
J 0
(-3375 2125);
FORCEPROP 1 LAST CUSTOM_TXT_CDS <Q_NUMBER>
J 0
(-1603 2053);
DISPLAY 1.212766 (-1603 2053);
FORCEPROP 1 LAST CUSTOM_TXT_CDS <Q_PROJ>
J 0
(-2582 2052);
DISPLAY 1.212766 (-2582 2052);
FORCEPROP 1 LAST CUSTOM_TXT_CDS <Q_REV>
J 0
(-384 2053);
DISPLAY 1.212766 (-384 2053);
FORCEPROP 1 LAST CUSTOM_TXT_CDS <CON_PAGE_NUM> OF <CON_TOTAL_PAGES>
J 0
(-646 1968);
DISPLAY 0.978723 (-646 1968);
FORCEPROP 1 LAST Q_TITLE BATTERY
J 0
(-9450 2025);
DISPLAY 2.446809 (-9450 2025);
PAINT GREEN (-9450 2025);
FORCEPROP 2 LAST CDS_LIB pure_quanta
J 0
(-200 1950);
DISPLAY INVISIBLE (-200 1950);
FORCEPROP 1 LAST CDS_LMAN_SYM_OUTLINE -9475,6775,100,-125
J 0
(-200 1950);
DISPLAY 0.468085 (-200 1950);
PAINT GREEN (-200 1950);
DISPLAY INVISIBLE (-200 1950);
FORCEPROP 2 LAST PAGE_BORDER TRUE
J 0
(-8090 7200);
DISPLAY 0.638298 (-8090 7200);
PAINT PINK (-8090 7200);
DISPLAY INVISIBLE (-8090 7200);
FORCEPROP 2 LAST CDS_XR_PAGE_TITLE CR-187 : @T6G_MB_LIB.T6G(SCH_1):PAGE187
J 0
(-8090 7200);
DISPLAY 0.638298 (-8090 7200);
PAINT PINK (-8090 7200);
DISPLAY INVISIBLE (-8090 7200);
FORCEPROP 1 LAST Q_DEPT BU9
J 1
(-3963 1999);
DISPLAY 1.957447 (-3963 1999);
PAINT GREEN (-3963 1999);
DISPLAY INVISIBLE (-3963 1999);
FORCEPROP 1 LAST COMMENT_BODY TRUE
J 0
(-188 1937);
DISPLAY 0.978723 (-188 1937);
PAINT GREEN (-188 1937);
DISPLAY INVISIBLE (-188 1937);
FORCEADD DNS..1
(-3225 3375);
PAINT RED (-3225 3375);
FORCEPROP 2 LAST CDS_LIB mstr_misc
J 0
(-3225 3375);
DISPLAY INVISIBLE (-3225 3375);
FORCEPROP 1 LAST COMMENT_BODY TRUE
R 1
J 0
(-3150 3150);
DISPLAY 0.872340 (-3150 3150);
PAINT GREEN (-3150 3150);
DISPLAY INVISIBLE (-3150 3150);
FORCEADD DNS..1
(-4725 3800);
PAINT RED (-4725 3800);
FORCEPROP 2 LAST CDS_LIB mstr_misc
J 0
(-4725 3800);
DISPLAY INVISIBLE (-4725 3800);
FORCEPROP 1 LAST COMMENT_BODY TRUE
R 1
J 0
(-4650 3575);
DISPLAY 0.872340 (-4650 3575);
PAINT GREEN (-4650 3575);
DISPLAY INVISIBLE (-4650 3575);
FORCEADD DNS..1
(-6300 6925);
PAINT RED (-6300 6925);
FORCEPROP 2 LAST CDS_LIB mstr_misc
J 0
(-6300 6925);
DISPLAY INVISIBLE (-6300 6925);
FORCEPROP 1 LAST COMMENT_BODY TRUE
R 1
J 0
(-6225 6700);
DISPLAY 0.872340 (-6225 6700);
PAINT GREEN (-6225 6700);
DISPLAY INVISIBLE (-6225 6700);
WIRE 16 -1 (-4650 6850)(-4675 6850);
WIRE 16 -1 (-4675 6850)(-4675 6650);
WIRE 16 -1 (-3250 3275)(-3250 3100);
WIRE 16 -1 (-3575 6450)(-3575 6675);
WIRE 16 -1 (-2075 5975)(-2075 6175);
WIRE 16 -1 (-1650 5975)(-1650 6175);
WIRE 16 -1 (-1800 7550)(-1900 7550);
WIRE 16 -1 (-1900 7550)(-1900 7375);
WIRE 16 -1 (-9325 6950)(-9400 6950);
WIRE 16 -1 (-9400 6950)(-9400 6500);
WIRE 16 -1 (-8275 7050)(-8525 7050);
WIRE 16 -1 (-8525 7050)(-8525 7350);
WIRE 16 -1 (-5125 3550)(-5375 3550);
WIRE 16 -1 (-5375 3550)(-5375 3500);
WIRE 16 -1 (-5525 7150)(-5400 7150);
WIRE 16 -1 (-5525 7150)(-5525 7000);
WIRE 16 -1 (-5525 7000)(-5425 7000);
FORCEPROP 2 LAST SIG_NAME P1V5_BAT_IN
J 0
(-5135 7000);
DISPLAY 0.489362 (-5135 7000);
WIRE 16 -1 (-6225 7000)(-5525 7000);
WIRE 16 -1 (-5425 7000)(-5250 7000);
WIRE 16 -1 (-5425 7000)(-5425 6875);
WIRE 16 -1 (-5250 7000)(-4825 7000);
WIRE 16 -1 (-5250 6900)(-5250 7000);
WIRE 16 -1 (-4825 7000)(-4650 7000);
WIRE 16 -1 (-4825 6450)(-4825 7000);
WIRE 16 -1 (-8925 6950)(-8275 6950);
FORCEPROP 2 LAST SIG_NAME P3V_BAT
J 0
(-8810 6960);
DISPLAY 0.489362 (-8810 6960);
FORCEPROP 2 LASTPROP $XRERR UNIQUE?
J 0
(-9050 6960);
DISPLAY 0.638298 (-9050 6960);
PAINT MONO (-9050 6960);
DISPLAY INVISIBLE (-9050 6960);
WIRE 16 -1 (-8075 6950)(-7750 6950);
FORCEPROP 2 LAST SIG_NAME P3V_BAT_R
J 0
(-7910 6975);
DISPLAY 0.489362 (-7910 6975);
WIRE 16 -1 (-7300 6950)(-7750 6950);
WIRE 16 -1 (-7750 6950)(-7750 6750);
WIRE 16 -1 (-7750 6750)(-7475 6750);
WIRE 16 -1 (-6550 7000)(-6550 7175);
WIRE 16 -1 (-6550 7000)(-6425 7000);
WIRE 16 -1 (-6550 7000)(-6850 7000);
WIRE 16 -1 (-7100 7000)(-6850 7000);
WIRE 16 -1 (-6850 7000)(-6850 7800);
WIRE 16 -1 (-5250 6475)(-5250 6700);
WIRE 16 -1 (-5425 6475)(-5250 6475);
WIRE 16 -1 (-5425 6675)(-5425 6475);
WIRE 16 -1 (-5425 6475)(-5425 6350);
WIRE 16 -1 (-1650 6375)(-1650 6700);
WIRE 16 -1 (-2075 6700)(-1650 6700);
WIRE 16 -1 (-2075 7600)(-2075 6700);
WIRE 16 -1 (-2075 6700)(-2075 6475);
WIRE 16 -1 (-2075 6475)(-2300 6475);
WIRE 16 -1 (-2075 6475)(-2075 6375);
WIRE 16 -1 (-1800 7600)(-2075 7600);
WIRE 16 -1 (-2300 6750)(-2300 6475);
WIRE 16 -1 (-2300 6475)(-2300 5700);
WIRE 16 -1 (-2875 5700)(-2300 5700);
WIRE 16 -1 (-6250 4600)(-6250 4725);
WIRE 16 -1 (-6250 4400)(-6250 4600);
WIRE 16 -1 (-6250 4600)(-6700 4600);
WIRE 16 -1 (-6700 4600)(-6700 4725);
WIRE 16 -1 (-8075 7050)(-7300 7050);
FORCEPROP 2 LAST SIG_NAME P3V3_STBY_R
J 0
(-7910 7060);
DISPLAY 0.489362 (-7910 7060);
FORCEPROP 2 LASTPROP $XRERR UNIQUE?
J 0
(-8150 7060);
DISPLAY 0.638298 (-8150 7060);
PAINT MONO (-8150 7060);
DISPLAY INVISIBLE (-8150 7060);
WIRE 16 -1 (-1800 7650)(-2300 7650);
FORCEPROP 0 LAST CDS_PHYS_NET_NAME P1V5_BAT_OUT_R
J 2
(-1825 7692);
PAINT MONO (-1825 7692);
DISPLAY INVISIBLE (-1825 7692);
FORCEPROP 2 LAST SIG_NAME P1V5_BAT_OUT_R
J 0
(-2260 7660);
DISPLAY 0.489362 (-2260 7660);
FORCEPROP 2 LASTPROP $XRERR UNIQUE?
J 0
(-2500 7660);
DISPLAY 0.638298 (-2500 7660);
PAINT MONO (-2500 7660);
DISPLAY INVISIBLE (-2500 7660);
WIRE 16 -1 (-2300 7000)(-2300 7650);
WIRE 16 -1 (-2300 7000)(-2750 7000);
WIRE 16 -1 (-2750 7425)(-2750 7000);
WIRE 16 -1 (-2975 7000)(-2750 7000);
WIRE 16 -1 (-5000 4975)(-3850 4975);
FORCEPROP 2 LAST SIG_NAME BAT_LDO_EN
J 0
(-4585 4985);
DISPLAY 0.617021 (-4585 4985);
WIRE 16 -1 (-3850 4975)(-3850 5900);
WIRE 16 -1 (-3850 5900)(-3850 6150);
WIRE 16 -1 (-4825 5900)(-3850 5900);
WIRE 16 -1 (-4825 6250)(-4825 5900);
WIRE 16 -1 (-3575 6150)(-3850 6150);
WIRE 16 -1 (-3850 6150)(-3850 6850);
WIRE 16 -1 (-3850 6850)(-3950 6850);
WIRE 16 -1 (-6550 7375)(-6550 7925);
WIRE 16 -1 (-6550 7925)(-2750 7925);
FORCEPROP 2 LAST SIG_NAME P3V3_RTC_AUX_R
J 0
(-4860 7960);
DISPLAY 0.489362 (-4860 7960);
FORCEPROP 2 LASTPROP $XRERR UNIQUE?
J 0
(-5100 7960);
DISPLAY 0.638298 (-5100 7960);
PAINT MONO (-5100 7960);
DISPLAY INVISIBLE (-5100 7960);
WIRE 16 -1 (-2750 7925)(-2750 7625);
WIRE 16 -1 (-3550 5700)(-3075 5700);
FORCEPROP 2 LAST SIG_NAME CLR_CMOS_N
J 0
(-3535 5710);
DISPLAY 0.489362 (-3535 5710);
FORCEPROP 2 LASTPROP $XRERR UNIQUE?
J 0
(-3775 5710);
DISPLAY 0.638298 (-3775 5710);
PAINT MONO (-3775 5710);
DISPLAY INVISIBLE (-3775 5710);
WIRE 16 -1 (-3550 4800)(-3550 5700);
WIRE 16 -1 (-5625 4800)(-3550 4800);
WIRE 16 -1 (-5625 4975)(-5625 4800);
WIRE 16 -1 (-5600 4975)(-5625 4975);
WIRE 16 -1 (-3175 7000)(-3575 7000);
FORCEPROP 2 LAST SIG_NAME P1V5_BAT_OUT
J 0
(-3510 7000);
DISPLAY 0.489362 (-3510 7000);
WIRE 16 -1 (-3575 7000)(-3575 6875);
WIRE 16 -1 (-3675 7000)(-3575 7000);
WIRE 16 -1 (-3675 7200)(-3675 7000);
WIRE 16 -1 (-3950 7000)(-3675 7000);
WIRE 16 -1 (-3675 7200)(-3575 7200);
WIRE 16 -1 (-5125 3650)(-6025 3650);
FORCEPROP 2 LAST SIG_NAME BAT_LDO_EN
J 0
(-5685 3660);
DISPLAY 0.489362 (-5685 3660);
WIRE 16 -1 (-5125 3750)(-6025 3750);
FORCEPROP 2 LAST SIG_NAME P1V5_BAT_IN
J 0
(-5685 3760);
DISPLAY 0.489362 (-5685 3760);
WIRE 16 -1 (-3400 3700)(-4325 3700);
FORCEPROP 2 LAST SIG_NAME P1V5_BAT_OUT
J 0
(-4185 3710);
DISPLAY 0.489362 (-4185 3710);
WIRE 16 -1 (-4325 3600)(-3250 3600);
FORCEPROP 2 LAST SIG_NAME U9_NR
J 0
(-4160 3625);
DISPLAY 0.680851 (-4160 3625);
FORCEPROP 2 LASTPROP $XRERR UNIQUE?
J 0
(-4400 3625);
DISPLAY 0.638298 (-4400 3625);
PAINT MONO (-4400 3625);
DISPLAY INVISIBLE (-4400 3625);
WIRE 16 -1 (-3250 3600)(-3250 3475);
WIRE 16 -1 (-6700 5025)(-6250 5025);
WIRE 16 -1 (-6700 4925)(-6700 5025);
WIRE 16 -1 (-6700 5025)(-7050 5025);
FORCEPROP 2 LAST SIG_NAME CLR_CMOS
J 0
(-6960 5035);
DISPLAY 0.489362 (-6960 5035);
WIRE 16 -1 (-6250 5025)(-5800 5025);
WIRE 16 -1 (-6250 5025)(-6250 4925);
WIRE 16 -1 (-5800 5025)(-5600 5025);
WIRE 16 -1 (-5800 4675)(-5800 5025);
WIRE 16 -1 (-4750 4675)(-5800 4675);
WIRE 16 -1 (-4750 5025)(-4750 4675);
WIRE 16 -1 (-5000 5025)(-4750 5025);
DOT 1 (-2075 6700);
DOT 1 (-2075 6475);
DOT 1 (-3575 7000);
DOT 1 (-3850 6150);
DOT 1 (-3850 5900);
DOT 1 (-5425 7000);
DOT 1 (-5525 7000);
DOT 1 (-5425 6475);
DOT 1 (-5800 5025);
DOT 1 (-6550 7000);
DOT 1 (-6850 7000);
DOT 1 (-6250 5025);
DOT 1 (-6700 5025);
DOT 1 (-6250 4600);
DOT 1 (-4825 7000);
DOT 1 (-2750 7000);
DOT 1 (-3675 7000);
DOT 1 (-2300 6475);
DOT 1 (-7750 6950);
DOT 1 (-5250 7000);
FORCENOTE
CLEAR CMOS JUMPER
(-2525 8325) 0;
DISPLAY LEFT (-2525 8325);
DISPLAY 1.595745 (-2525 8325);
FORCENOTE
1-2 NORMAL OPERATION(DEFAULT)
(-2525 8200) 0;
DISPLAY LEFT (-2525 8200);
DISPLAY 1.595745 (-2525 8200);
FORCENOTE
2-3 BIOS LOAD DEFAULT
(-2525 8075) 0;
DISPLAY LEFT (-2525 8075);
DISPLAY 1.595745 (-2525 8075);
FORCENOTE
2ND SOURCE OF U167
(-5400 3200) 0;
DISPLAY LEFT (-5400 3200);
DISPLAY 1.595745 (-5400 3200);
FORCENOTE
FPGA
(-7025 5200) 0;
DISPLAY LEFT (-7025 5200);
DISPLAY 2.000000 (-7025 5200);
PAINT WHITE (-7025 5200);
FORCENOTE
CAD NOTE: R5053 R5054 CO-LAY
(-3750 7275) 0;
DISPLAY LEFT (-3750 7275);
DISPLAY 1.021277 (-3750 7275);
FORCENOTE
CAD NOTE:
(-9275 6150) 0;
DISPLAY LEFT (-9275 6150);
DISPLAY 1.021277 (-9275 6150);
FORCENOTE
VDDBT_RTC_G POWERED FROM 1.5 OR 1.8V: POP R5051 R5053 R5056, DEPOP R5052 R5054 R5055
(-9275 6066) 0;
DISPLAY LEFT (-9275 6066);
DISPLAY 1.021277 (-9275 6066);
FORCENOTE
AHL03003097
(-9275 6000) 0;
DISPLAY LEFT (-9275 6000);
DISPLAY 1.021277 (-9275 6000);
FORCENOTE
VDDBT_RTC_G POWERED FROM 3V: POP R5052 R5054 R5055,DEPOP R5051 R5053 R5056
(-9275 5934) 0;
DISPLAY LEFT (-9275 5934);
DISPLAY 1.021277 (-9275 5934);
FORCENOTE
CAD NOTE: R5051 R5052 CO-LAY
(-6300 7225) 0;
DISPLAY LEFT (-6300 7225);
DISPLAY 1.021277 (-6300 7225);
QUIT
